FILE_TYPE = MULTI_PHYS_TABLE;
PART 'M25PE16'
{============================================================================================================================================================================================}
:PACK_TYPE | MATERIAL | PART_NUMBER     = EnvComp | PART_NUMBER  | JEDEC_TYPE        | DESCRIPTION                                 | CLASS | COMPONENT_TYPE | HEIGHT     | LPID  | SPEED_URL | Status |RPL| AML | Bus_Unit | Days;
{============================================================================================================================================================================================}
'SM'       | 'IC'     | 'H77797-001'(!) = ''      | 'H77797-001' | 'SOI8_20_50IA'    | 'IC,FLASH,SPI SERIAL FLASH,SOIC,8,16 MBIT'  | 'IC'  | 'SOIC'         | '0.085 IN' | '323' | 'http://speed.intel.com:8081/speed/module/pdm/item/pdm_item_detail_direct.asp?item_cde=H77797-001&item_rev=01&url_param=unused' | '' | '' | '' | '' | '' 
'SM'       | 'EMPTY'  | 'H77797-001'(!) = ''      | 'H77797-001' | 'SOI8_20_50IA'    | 'IC,FLASH,SPI SERIAL FLASH,SOIC,8,16 MBIT'  | 'IO'  | 'SOIC'         | '0.085 IN' | '323' | 'http://speed.intel.com:8081/speed/module/pdm/item/pdm_item_detail_direct.asp?item_cde=H77797-001&item_rev=01&url_param=unused' | '' | '' | '' | '' | '' 
END_PART
END.
